(kicad_pcb
	(version 20260206)
	(generator "pcbnew")
	(generator_version "10.0")
	(general
		(thickness 1.6)
		(legacy_teardrops no)
	)
	(paper "A4")
	(title_block
		(title "03242023_DA0F0TMBIJ0_F0T_Motherboard_J_brd_V01_OCP.brd")
		(comment 1 "Grand Teton / footprints 804-809 of 6105")
	)
	(layers
		(0 "F.Cu" signal "TOP")
		(4 "In1.Cu" signal "GND")
		(6 "In2.Cu" signal "IN1")
		(8 "In3.Cu" signal "GND1")
		(10 "In4.Cu" signal "IN2")
		(12 "In5.Cu" signal "GND2")
		(14 "In6.Cu" signal "IN3")
		(16 "In7.Cu" signal "GND3")
		(18 "In8.Cu" signal "VCC")
		(20 "In9.Cu" signal "VCC1")
		(22 "In10.Cu" signal "GND4")
		(24 "In11.Cu" signal "IN4")
		(26 "In12.Cu" signal "GND5")
		(28 "In13.Cu" signal "IN5")
		(30 "In14.Cu" signal "GND6")
		(32 "In15.Cu" signal "IN6")
		(34 "In16.Cu" signal "GND7")
		(2 "B.Cu" signal "BOTTOM")
		(9 "F.Adhes" user "F.Adhesive")
		(11 "B.Adhes" user "B.Adhesive")
		(13 "F.Paste" user "Package Geometry/Pastemask Top")
		(15 "B.Paste" user "Package Geometry/Pastemask Bottom")
		(5 "F.SilkS" user "Ref Des/Silkscreen Top")
		(7 "B.SilkS" user "Ref Des/Silkscreen Bottom")
		(1 "F.Mask" user "Board Geometry/Soldermask Top")
		(3 "B.Mask" user "Board Geometry/Soldermask Bottom")
		(17 "Dwgs.User" user "User.Drawings")
		(19 "Cmts.User" user "User.Comments")
		(21 "Eco1.User" user "User.Eco1")
		(23 "Eco2.User" user "User.Eco2")
		(25 "Edge.Cuts" user "Board Geometry/Outline")
		(27 "Margin" user)
		(31 "F.CrtYd" user "Package Geometry/Place Bound Top")
		(29 "B.CrtYd" user "Package Geometry/Place Bound Bottom")
		(35 "F.Fab" user "Ref Des/Assembly Top")
		(33 "B.Fab" user "Ref Des/Assembly Bottom")
	)
	(footprint ""
		(layer "F.Cu")
		(at 176.078388 -416.729418 180)
		(property "Reference" "R3436"
			(at 0 0 180)
			(layer "F.SilkS")
			(hide yes)
			(effects
				(font
					(size 1.27 1.27)
				)
			)
		)
		(property "Value" ""
			(at 0 0 180)
			(layer "F.Fab")
			(effects
				(font
					(size 1.27 1.27)
				)
			)
		)
		(duplicate_pad_numbers_are_jumpers no)
		(fp_line
			(start 0.7874 0.4064)
			(end -0.7874 0.4064)
			(stroke
				(width 0.1524)
				(type default)
			)
			(layer "F.SilkS")
		)
		(fp_line
			(start 0.7874 -0.4064)
			(end 0.7874 0.4064)
			(stroke
				(width 0.1524)
				(type default)
			)
			(layer "F.SilkS")
		)
		(fp_line
			(start -0.7874 0.4064)
			(end -0.7874 -0.4064)
			(stroke
				(width 0.1524)
				(type default)
			)
			(layer "F.SilkS")
		)
		(fp_line
			(start -0.7874 -0.4064)
			(end 0.7874 -0.4064)
			(stroke
				(width 0.1524)
				(type default)
			)
			(layer "F.SilkS")
		)
		(fp_line
			(start 0.67945 0.3048)
			(end 0.120396 0.3048)
			(stroke
				(width 0.1)
				(type default)
			)
			(layer "F.Fab")
		)
		(fp_line
			(start 0.67945 -0.3048)
			(end 0.67945 0.3048)
			(stroke
				(width 0.1)
				(type default)
			)
			(layer "F.Fab")
		)
		(fp_line
			(start 0.12065 -0.2794)
			(end 0.12065 -0.3048)
			(stroke
				(width 0.1)
				(type default)
			)
			(layer "F.Fab")
		)
		(fp_line
			(start 0.12065 -0.3048)
			(end 0.67945 -0.3048)
			(stroke
				(width 0.1)
				(type default)
			)
			(layer "F.Fab")
		)
		(fp_line
			(start 0.120396 0.3048)
			(end 0.120396 0.2794)
			(stroke
				(width 0.1)
				(type default)
			)
			(layer "F.Fab")
		)
		(fp_line
			(start 0.120396 0.2794)
			(end -0.12065 0.2794)
			(stroke
				(width 0.1)
				(type default)
			)
			(layer "F.Fab")
		)
		(fp_line
			(start -0.12065 0.3048)
			(end -0.67945 0.3048)
			(stroke
				(width 0.1)
				(type default)
			)
			(layer "F.Fab")
		)
		(fp_line
			(start -0.12065 0.2794)
			(end -0.12065 0.3048)
			(stroke
				(width 0.1)
				(type default)
			)
			(layer "F.Fab")
		)
		(fp_line
			(start -0.12065 -0.2794)
			(end 0.12065 -0.2794)
			(stroke
				(width 0.1)
				(type default)
			)
			(layer "F.Fab")
		)
		(fp_line
			(start -0.12065 -0.305054)
			(end -0.12065 -0.2794)
			(stroke
				(width 0.1)
				(type default)
			)
			(layer "F.Fab")
		)
		(fp_line
			(start -0.67945 0.3048)
			(end -0.67945 -0.305054)
			(stroke
				(width 0.1)
				(type default)
			)
			(layer "F.Fab")
		)
		(fp_line
			(start -0.67945 -0.305054)
			(end -0.12065 -0.305054)
			(stroke
				(width 0.1)
				(type default)
			)
			(layer "F.Fab")
		)
		(pad "1" smd circle
			(at -0.40005 0 180)
			(size 0 0)
			(layers "F.Cu" "F.Mask" "F.Paste")
			(net "P3V3_AUX")
		)
		(pad "2" smd circle
			(at 0.40005 0 180)
			(size 0 0)
			(layers "F.Cu" "F.Mask" "F.Paste")
			(net "GPU_HMC_PRSNT_ISO_N")
		)
	)
	(footprint ""
		(layer "F.Cu")
		(at 118.86184 -413.189928 180)
		(property "Reference" "R4476"
			(at 0 0 180)
			(layer "F.SilkS")
			(hide yes)
			(effects
				(font
					(size 1.27 1.27)
				)
			)
		)
		(property "Value" ""
			(at 0 0 180)
			(layer "F.Fab")
			(effects
				(font
					(size 1.27 1.27)
				)
			)
		)
		(duplicate_pad_numbers_are_jumpers no)
		(fp_line
			(start 0.7874 0.4064)
			(end -0.7874 0.4064)
			(stroke
				(width 0.1524)
				(type default)
			)
			(layer "F.SilkS")
		)
		(fp_line
			(start 0.7874 -0.4064)
			(end 0.7874 0.4064)
			(stroke
				(width 0.1524)
				(type default)
			)
			(layer "F.SilkS")
		)
		(fp_line
			(start -0.7874 0.4064)
			(end -0.7874 -0.4064)
			(stroke
				(width 0.1524)
				(type default)
			)
			(layer "F.SilkS")
		)
		(fp_line
			(start -0.7874 -0.4064)
			(end 0.7874 -0.4064)
			(stroke
				(width 0.1524)
				(type default)
			)
			(layer "F.SilkS")
		)
		(fp_line
			(start 0.67945 0.3048)
			(end 0.120396 0.3048)
			(stroke
				(width 0.1)
				(type default)
			)
			(layer "F.Fab")
		)
		(fp_line
			(start 0.67945 -0.3048)
			(end 0.67945 0.3048)
			(stroke
				(width 0.1)
				(type default)
			)
			(layer "F.Fab")
		)
		(fp_line
			(start 0.12065 -0.2794)
			(end 0.12065 -0.3048)
			(stroke
				(width 0.1)
				(type default)
			)
			(layer "F.Fab")
		)
		(fp_line
			(start 0.12065 -0.3048)
			(end 0.67945 -0.3048)
			(stroke
				(width 0.1)
				(type default)
			)
			(layer "F.Fab")
		)
		(fp_line
			(start 0.120396 0.3048)
			(end 0.120396 0.2794)
			(stroke
				(width 0.1)
				(type default)
			)
			(layer "F.Fab")
		)
		(fp_line
			(start 0.120396 0.2794)
			(end -0.12065 0.2794)
			(stroke
				(width 0.1)
				(type default)
			)
			(layer "F.Fab")
		)
		(fp_line
			(start -0.12065 0.3048)
			(end -0.67945 0.3048)
			(stroke
				(width 0.1)
				(type default)
			)
			(layer "F.Fab")
		)
		(fp_line
			(start -0.12065 0.2794)
			(end -0.12065 0.3048)
			(stroke
				(width 0.1)
				(type default)
			)
			(layer "F.Fab")
		)
		(fp_line
			(start -0.12065 -0.2794)
			(end 0.12065 -0.2794)
			(stroke
				(width 0.1)
				(type default)
			)
			(layer "F.Fab")
		)
		(fp_line
			(start -0.12065 -0.305054)
			(end -0.12065 -0.2794)
			(stroke
				(width 0.1)
				(type default)
			)
			(layer "F.Fab")
		)
		(fp_line
			(start -0.67945 0.3048)
			(end -0.67945 -0.305054)
			(stroke
				(width 0.1)
				(type default)
			)
			(layer "F.Fab")
		)
		(fp_line
			(start -0.67945 -0.305054)
			(end -0.12065 -0.305054)
			(stroke
				(width 0.1)
				(type default)
			)
			(layer "F.Fab")
		)
		(pad "1" smd circle
			(at -0.40005 0 180)
			(size 0 0)
			(layers "F.Cu" "F.Mask" "F.Paste")
			(net "FM_PLD_CLKS_DEV_EN")
		)
		(pad "2" smd circle
			(at 0.40005 0 180)
			(size 0 0)
			(layers "F.Cu" "F.Mask" "F.Paste")
			(net "FM_9ZXL045_DEV_EN")
		)
	)
	(footprint ""
		(layer "F.Cu")
		(at 28.081732 -411.434534)
		(property "Reference" "Q107"
			(at 0.0508 -2.306828 0)
			(unlocked yes)
			(layer "F.SilkS")
			(effects
				(font
					(size 0.7874 0.5842)
					(thickness 0.1524)
				)
				(justify left)
			)
		)
		(property "Value" ""
			(at 0 0 0)
			(layer "F.Fab")
			(effects
				(font
					(size 1.27 1.27)
				)
			)
		)
		(duplicate_pad_numbers_are_jumpers no)
		(fp_line
			(start -1.332738 -1.100074)
			(end -0.4826 -1.100074)
			(stroke
				(width 0.1524)
				(type default)
			)
			(layer "F.SilkS")
		)
		(fp_line
			(start -1.332738 1.100074)
			(end -1.332738 -1.100074)
			(stroke
				(width 0.1524)
				(type default)
			)
			(layer "F.SilkS")
		)
		(fp_line
			(start -0.4826 -1.100074)
			(end 0 -0.541274)
			(stroke
				(width 0.1524)
				(type default)
			)
			(layer "F.SilkS")
		)
		(fp_line
			(start 0 -0.541274)
			(end 0.4826 -1.100074)
			(stroke
				(width 0.1524)
				(type default)
			)
			(layer "F.SilkS")
		)
		(fp_line
			(start 0.4826 -1.100074)
			(end 1.332738 -1.100074)
			(stroke
				(width 0.1524)
				(type default)
			)
			(layer "F.SilkS")
		)
		(fp_line
			(start 1.332738 -1.100074)
			(end 1.332738 1.100074)
			(stroke
				(width 0.1524)
				(type default)
			)
			(layer "F.SilkS")
		)
		(fp_line
			(start 1.332738 1.100074)
			(end -1.332738 1.100074)
			(stroke
				(width 0.1524)
				(type default)
			)
			(layer "F.SilkS")
		)
		(fp_poly
			(pts
				(xy -0.542544 -1.945132) (xy -0.893572 -1.24333) (xy -1.2446 -1.945132)
			)
			(stroke
				(width 0)
				(type default)
			)
			(fill yes)
			(layer "F.SilkS")
		)
		(fp_line
			(start -0.674878 -1.100074)
			(end 0.674878 -1.100074)
			(stroke
				(width 0.1)
				(type default)
			)
			(layer "F.Fab")
		)
		(fp_line
			(start -0.674878 1.100074)
			(end -0.674878 -1.100074)
			(stroke
				(width 0.1)
				(type default)
			)
			(layer "F.Fab")
		)
		(fp_line
			(start 0.674878 -1.100074)
			(end 0.674878 1.100074)
			(stroke
				(width 0.1)
				(type default)
			)
			(layer "F.Fab")
		)
		(fp_line
			(start 0.674878 1.100074)
			(end -0.674878 1.100074)
			(stroke
				(width 0.1)
				(type default)
			)
			(layer "F.Fab")
		)
		(fp_poly
			(pts
				(xy -2.2352 -0.298958) (xy -2.2352 -1.001014) (xy -1.533144 -0.649986)
			)
			(stroke
				(width 0)
				(type default)
			)
			(fill yes)
			(layer "F.Fab")
		)
		(pad "1" smd rect
			(at -0.94996 -0.649986 90)
			(size 0.4318 0.508)
			(layers "F.Cu" "F.Mask" "F.Paste")
			(net "GND")
		)
		(pad "2" smd rect
			(at -0.94996 0 90)
			(size 0.4318 0.508)
			(layers "F.Cu" "F.Mask" "F.Paste")
			(net "GPU_PRSNT_N")
		)
		(pad "3" smd rect
			(at -0.94996 0.649986 90)
			(size 0.4318 0.508)
			(layers "F.Cu" "F.Mask" "F.Paste")
			(net "GPU_PRSNT_N_ISO")
		)
		(pad "4" smd rect
			(at 0.94996 0.649986 90)
			(size 0.4318 0.508)
			(layers "F.Cu" "F.Mask" "F.Paste")
			(net "GND")
		)
		(pad "5" smd rect
			(at 0.94996 0 90)
			(size 0.4318 0.508)
			(layers "F.Cu" "F.Mask" "F.Paste")
			(net "GPU_PRSNT")
		)
		(pad "6" smd rect
			(at 0.94996 -0.649986 90)
			(size 0.4318 0.508)
			(layers "F.Cu" "F.Mask" "F.Paste")
			(net "GPU_PRSNT")
		)
	)
	(footprint ""
		(layer "F.Cu")
		(at 87.935562 -53.880258 90)
		(property "Reference" "PR4523"
			(at 0 0 90)
			(layer "F.SilkS")
			(hide yes)
			(effects
				(font
					(size 1.27 1.27)
				)
			)
		)
		(property "Value" ""
			(at 0 0 90)
			(layer "F.Fab")
			(effects
				(font
					(size 1.27 1.27)
				)
			)
		)
		(duplicate_pad_numbers_are_jumpers no)
		(fp_line
			(start 0.7874 -0.4064)
			(end 0.7874 0.4064)
			(stroke
				(width 0.1524)
				(type default)
			)
			(layer "F.SilkS")
		)
		(fp_line
			(start -0.7874 -0.4064)
			(end 0.7874 -0.4064)
			(stroke
				(width 0.1524)
				(type default)
			)
			(layer "F.SilkS")
		)
		(fp_line
			(start 0.7874 0.4064)
			(end -0.7874 0.4064)
			(stroke
				(width 0.1524)
				(type default)
			)
			(layer "F.SilkS")
		)
		(fp_line
			(start -0.7874 0.4064)
			(end -0.7874 -0.4064)
			(stroke
				(width 0.1524)
				(type default)
			)
			(layer "F.SilkS")
		)
		(fp_line
			(start -0.12065 -0.305054)
			(end -0.12065 -0.2794)
			(stroke
				(width 0.1)
				(type default)
			)
			(layer "F.Fab")
		)
		(fp_line
			(start -0.67945 -0.305054)
			(end -0.12065 -0.305054)
			(stroke
				(width 0.1)
				(type default)
			)
			(layer "F.Fab")
		)
		(fp_line
			(start 0.67945 -0.3048)
			(end 0.67945 0.3048)
			(stroke
				(width 0.1)
				(type default)
			)
			(layer "F.Fab")
		)
		(fp_line
			(start 0.12065 -0.3048)
			(end 0.67945 -0.3048)
			(stroke
				(width 0.1)
				(type default)
			)
			(layer "F.Fab")
		)
		(fp_line
			(start 0.12065 -0.2794)
			(end 0.12065 -0.3048)
			(stroke
				(width 0.1)
				(type default)
			)
			(layer "F.Fab")
		)
		(fp_line
			(start -0.12065 -0.2794)
			(end 0.12065 -0.2794)
			(stroke
				(width 0.1)
				(type default)
			)
			(layer "F.Fab")
		)
		(fp_line
			(start 0.120396 0.2794)
			(end -0.12065 0.2794)
			(stroke
				(width 0.1)
				(type default)
			)
			(layer "F.Fab")
		)
		(fp_line
			(start -0.12065 0.2794)
			(end -0.12065 0.3048)
			(stroke
				(width 0.1)
				(type default)
			)
			(layer "F.Fab")
		)
		(fp_line
			(start 0.67945 0.3048)
			(end 0.120396 0.3048)
			(stroke
				(width 0.1)
				(type default)
			)
			(layer "F.Fab")
		)
		(fp_line
			(start 0.120396 0.3048)
			(end 0.120396 0.2794)
			(stroke
				(width 0.1)
				(type default)
			)
			(layer "F.Fab")
		)
		(fp_line
			(start -0.12065 0.3048)
			(end -0.67945 0.3048)
			(stroke
				(width 0.1)
				(type default)
			)
			(layer "F.Fab")
		)
		(fp_line
			(start -0.67945 0.3048)
			(end -0.67945 -0.305054)
			(stroke
				(width 0.1)
				(type default)
			)
			(layer "F.Fab")
		)
		(pad "1" smd circle
			(at -0.40005 0 90)
			(size 0 0)
			(layers "F.Cu" "F.Mask" "F.Paste")
			(net "P3V3_OCP_V3_2_R")
		)
		(pad "2" smd circle
			(at 0.40005 0 90)
			(size 0 0)
			(layers "F.Cu" "F.Mask" "F.Paste")
			(net "P3V3_OCP_GATE_2")
		)
	)
	(footprint ""
		(layer "F.Cu")
		(at 406.779984 -16.088614 90)
		(property "Reference" "C851"
			(at 0 0 90)
			(layer "F.SilkS")
			(hide yes)
			(effects
				(font
					(size 1.27 1.27)
				)
			)
		)
		(property "Value" ""
			(at 0 0 90)
			(layer "F.Fab")
			(effects
				(font
					(size 1.27 1.27)
				)
			)
		)
		(duplicate_pad_numbers_are_jumpers no)
		(fp_line
			(start 0.299974 -0.150114)
			(end 0.299974 0.150114)
			(stroke
				(width 0.1)
				(type default)
			)
			(layer "F.Fab")
		)
		(fp_line
			(start -0.299974 -0.150114)
			(end 0.299974 -0.150114)
			(stroke
				(width 0.1)
				(type default)
			)
			(layer "F.Fab")
		)
		(fp_line
			(start 0.299974 0.150114)
			(end -0.299974 0.150114)
			(stroke
				(width 0.1)
				(type default)
			)
			(layer "F.Fab")
		)
		(fp_line
			(start -0.299974 0.150114)
			(end -0.299974 -0.150114)
			(stroke
				(width 0.1)
				(type default)
			)
			(layer "F.Fab")
		)
		(pad "1" smd rect
			(at -0.2667 0 90)
			(size 0.3048 0.381)
			(layers "F.Cu" "F.Mask" "F.Paste")
			(net "P5E_CPU0_PE1_TX_C_DP<9>")
		)
		(pad "2" smd rect
			(at 0.2667 0 90)
			(size 0.3048 0.381)
			(layers "F.Cu" "F.Mask" "F.Paste")
			(net "P5E_CPU0_PE1_TX_DP<9>")
		)
	)
	(footprint ""
		(layer "F.Cu")
		(at 353.242626 -238.160052 90)
		(property "Reference" "C590"
			(at 0 0 90)
			(layer "F.SilkS")
			(hide yes)
			(effects
				(font
					(size 1.27 1.27)
				)
			)
		)
		(property "Value" ""
			(at 0 0 90)
			(layer "F.Fab")
			(effects
				(font
					(size 1.27 1.27)
				)
			)
		)
		(duplicate_pad_numbers_are_jumpers no)
		(fp_line
			(start 0.7874 -0.4064)
			(end 0.7874 0.4064)
			(stroke
				(width 0.1524)
				(type default)
			)
			(layer "F.SilkS")
		)
		(fp_line
			(start -0.7874 -0.4064)
			(end 0.7874 -0.4064)
			(stroke
				(width 0.1524)
				(type default)
			)
			(layer "F.SilkS")
		)
		(fp_line
			(start 0.7874 0.4064)
			(end -0.7874 0.4064)
			(stroke
				(width 0.1524)
				(type default)
			)
			(layer "F.SilkS")
		)
		(fp_line
			(start -0.7874 0.4064)
			(end -0.7874 -0.4064)
			(stroke
				(width 0.1524)
				(type default)
			)
			(layer "F.SilkS")
		)
		(fp_line
			(start -0.12065 -0.305054)
			(end -0.12065 -0.2794)
			(stroke
				(width 0.1)
				(type default)
			)
			(layer "F.Fab")
		)
		(fp_line
			(start -0.67945 -0.305054)
			(end -0.12065 -0.305054)
			(stroke
				(width 0.1)
				(type default)
			)
			(layer "F.Fab")
		)
		(fp_line
			(start 0.67945 -0.3048)
			(end 0.67945 0.3048)
			(stroke
				(width 0.1)
				(type default)
			)
			(layer "F.Fab")
		)
		(fp_line
			(start 0.12065 -0.3048)
			(end 0.67945 -0.3048)
			(stroke
				(width 0.1)
				(type default)
			)
			(layer "F.Fab")
		)
		(fp_line
			(start 0.12065 -0.2794)
			(end 0.12065 -0.3048)
			(stroke
				(width 0.1)
				(type default)
			)
			(layer "F.Fab")
		)
		(fp_line
			(start -0.12065 -0.2794)
			(end 0.12065 -0.2794)
			(stroke
				(width 0.1)
				(type default)
			)
			(layer "F.Fab")
		)
		(fp_line
			(start 0.120396 0.2794)
			(end -0.12065 0.2794)
			(stroke
				(width 0.1)
				(type default)
			)
			(layer "F.Fab")
		)
		(fp_line
			(start -0.12065 0.2794)
			(end -0.12065 0.3048)
			(stroke
				(width 0.1)
				(type default)
			)
			(layer "F.Fab")
		)
		(fp_line
			(start 0.67945 0.3048)
			(end 0.120396 0.3048)
			(stroke
				(width 0.1)
				(type default)
			)
			(layer "F.Fab")
		)
		(fp_line
			(start 0.120396 0.3048)
			(end 0.120396 0.2794)
			(stroke
				(width 0.1)
				(type default)
			)
			(layer "F.Fab")
		)
		(fp_line
			(start -0.12065 0.3048)
			(end -0.67945 0.3048)
			(stroke
				(width 0.1)
				(type default)
			)
			(layer "F.Fab")
		)
		(fp_line
			(start -0.67945 0.3048)
			(end -0.67945 -0.305054)
			(stroke
				(width 0.1)
				(type default)
			)
			(layer "F.Fab")
		)
		(pad "1" smd circle
			(at -0.40005 0 90)
			(size 0 0)
			(layers "F.Cu" "F.Mask" "F.Paste")
			(net "PVNN_MAIN_CPU0")
		)
		(pad "2" smd circle
			(at 0.40005 0 90)
			(size 0 0)
			(layers "F.Cu" "F.Mask" "F.Paste")
			(net "GND")
		)
	)
)
